# T6G (Grand Teton) — schematic netlist excerpt (pin names and nets, part order shuffled) for the footprints in the layout excerpt that follows; sources: Cadence DE-HDL packaged netlist, KiCad conversion of 04192023_DAF0TMB3IC0_F0TG_MB_C_brd_V02_OCP.brd

PC186  Q_CAP  0.22UF 16V 10% X7R  pkg 0402  page 206 : A = SW_PVDDIO_P0_BOOT3_R ; B = SW_PVDDIO_P0_BOOTR3
PC179_3  Q_CAP  1UF 25V 10% X6S  pkg C0402  page 206 : A = SW_P12V_AUX_PVDDIO_P0_FLT ; B = GND

(kicad_pcb
	(version 20260206)
	(generator "pcbnew")
	(generator_version "10.0")
	(general
		(thickness 1.6)
		(legacy_teardrops no)
	)
	(paper "A4")
	(title_block
		(title "04192023_DAF0TMB3IC0_F0TG_MB_C_brd_V02_OCP.brd")
		(comment 1 "Grand Teton / footprints 2141-2142 of 8354")
	)
	(layers
		(0 "F.Cu" signal "TOP")
		(4 "In1.Cu" signal "GND")
		(6 "In2.Cu" signal "IN1")
		(8 "In3.Cu" signal "GND1")
		(10 "In4.Cu" signal "IN2")
		(12 "In5.Cu" signal "GND2")
		(14 "In6.Cu" signal "IN3")
		(16 "In7.Cu" signal "GND3")
		(18 "In8.Cu" signal "VCC")
		(20 "In9.Cu" signal "VCC1")
		(22 "In10.Cu" signal "GND4")
		(24 "In11.Cu" signal "IN4")
		(26 "In12.Cu" signal "GND5")
		(28 "In13.Cu" signal "IN5")
		(30 "In14.Cu" signal "GND6")
		(32 "In15.Cu" signal "IN6")
		(34 "In16.Cu" signal "GND7")
		(2 "B.Cu" signal "BOTTOM")
		(9 "F.Adhes" user "F.Adhesive")
		(11 "B.Adhes" user "B.Adhesive")
		(13 "F.Paste" user "Package Geometry/Pastemask Top")
		(15 "B.Paste" user "Package Geometry/Pastemask Bottom")
		(5 "F.SilkS" user "Ref Des/Silkscreen Top")
		(7 "B.SilkS" user "Ref Des/Silkscreen Bottom")
		(1 "F.Mask" user "Board Geometry/Soldermask Top")
		(3 "B.Mask" user "Board Geometry/Soldermask Bottom")
		(17 "Dwgs.User" user "User.Drawings")
		(19 "Cmts.User" user "User.Comments")
		(21 "Eco1.User" user "User.Eco1")
		(23 "Eco2.User" user "User.Eco2")
		(25 "Edge.Cuts" user "Board Geometry/Outline")
		(27 "Margin" user)
		(31 "F.CrtYd" user "Package Geometry/Place Bound Top")
		(29 "B.CrtYd" user "Package Geometry/Place Bound Bottom")
		(35 "F.Fab" user "Ref Des/Assembly Top")
		(33 "B.Fab" user "Ref Des/Assembly Bottom")
	)
	(footprint ""
		(layer "F.Cu")
		(at 285.48838 -351.368106 -90)
		(property "Reference" "PC186"
			(at 0 0 270)
			(layer "F.SilkS")
			(hide yes)
			(effects
				(font
					(size 1.27 1.27)
				)
			)
		)
		(property "Value" ""
			(at 0 0 270)
			(layer "F.Fab")
			(effects
				(font
					(size 1.27 1.27)
				)
			)
		)
		(duplicate_pad_numbers_are_jumpers no)
		(fp_line
			(start -0.7874 0.4064)
			(end -0.7874 -0.4064)
			(stroke
				(width 0.1524)
				(type default)
			)
			(layer "F.SilkS")
		)
		(fp_line
			(start 0.7874 0.4064)
			(end -0.7874 0.4064)
			(stroke
				(width 0.1524)
				(type default)
			)
			(layer "F.SilkS")
		)
		(fp_line
			(start -0.7874 -0.4064)
			(end 0.7874 -0.4064)
			(stroke
				(width 0.1524)
				(type default)
			)
			(layer "F.SilkS")
		)
		(fp_line
			(start 0.7874 -0.4064)
			(end 0.7874 0.4064)
			(stroke
				(width 0.1524)
				(type default)
			)
			(layer "F.SilkS")
		)
		(fp_line
			(start -0.67945 0.3048)
			(end -0.67945 -0.305054)
			(stroke
				(width 0.1)
				(type default)
			)
			(layer "F.Fab")
		)
		(fp_line
			(start -0.12065 0.3048)
			(end -0.67945 0.3048)
			(stroke
				(width 0.1)
				(type default)
			)
			(layer "F.Fab")
		)
		(fp_line
			(start 0.120396 0.3048)
			(end 0.120396 0.2794)
			(stroke
				(width 0.1)
				(type default)
			)
			(layer "F.Fab")
		)
		(fp_line
			(start 0.67945 0.3048)
			(end 0.120396 0.3048)
			(stroke
				(width 0.1)
				(type default)
			)
			(layer "F.Fab")
		)
		(fp_line
			(start -0.12065 0.2794)
			(end -0.12065 0.3048)
			(stroke
				(width 0.1)
				(type default)
			)
			(layer "F.Fab")
		)
		(fp_line
			(start 0.120396 0.2794)
			(end -0.12065 0.2794)
			(stroke
				(width 0.1)
				(type default)
			)
			(layer "F.Fab")
		)
		(fp_line
			(start -0.12065 -0.2794)
			(end 0.12065 -0.2794)
			(stroke
				(width 0.1)
				(type default)
			)
			(layer "F.Fab")
		)
		(fp_line
			(start 0.12065 -0.2794)
			(end 0.12065 -0.3048)
			(stroke
				(width 0.1)
				(type default)
			)
			(layer "F.Fab")
		)
		(fp_line
			(start 0.12065 -0.3048)
			(end 0.67945 -0.3048)
			(stroke
				(width 0.1)
				(type default)
			)
			(layer "F.Fab")
		)
		(fp_line
			(start 0.67945 -0.3048)
			(end 0.67945 0.3048)
			(stroke
				(width 0.1)
				(type default)
			)
			(layer "F.Fab")
		)
		(fp_line
			(start -0.67945 -0.305054)
			(end -0.12065 -0.305054)
			(stroke
				(width 0.1)
				(type default)
			)
			(layer "F.Fab")
		)
		(fp_line
			(start -0.12065 -0.305054)
			(end -0.12065 -0.2794)
			(stroke
				(width 0.1)
				(type default)
			)
			(layer "F.Fab")
		)
		(pad "1" smd circle
			(at -0.40005 0 270)
			(size 0 0)
			(layers "F.Cu" "F.Mask" "F.Paste")
			(net "SW_PVDDIO_P0_BOOT3_R")
		)
		(pad "2" smd circle
			(at 0.40005 0 270)
			(size 0 0)
			(layers "F.Cu" "F.Mask" "F.Paste")
			(net "SW_PVDDIO_P0_BOOTR3")
		)
	)
	(footprint ""
		(layer "F.Cu")
		(at 287.336992 -346.866464 -90)
		(property "Reference" "PC179_3"
			(at 0 0 270)
			(layer "F.SilkS")
			(hide yes)
			(effects
				(font
					(size 1.27 1.27)
				)
			)
		)
		(property "Value" ""
			(at 0 0 270)
			(layer "F.Fab")
			(effects
				(font
					(size 1.27 1.27)
				)
			)
		)
		(duplicate_pad_numbers_are_jumpers no)
		(fp_line
			(start -0.7874 0.4064)
			(end -0.7874 -0.4064)
			(stroke
				(width 0.1524)
				(type default)
			)
			(layer "F.SilkS")
		)
		(fp_line
			(start 0.7874 0.4064)
			(end -0.7874 0.4064)
			(stroke
				(width 0.1524)
				(type default)
			)
			(layer "F.SilkS")
		)
		(fp_line
			(start -0.7874 -0.4064)
			(end 0.7874 -0.4064)
			(stroke
				(width 0.1524)
				(type default)
			)
			(layer "F.SilkS")
		)
		(fp_line
			(start 0.7874 -0.4064)
			(end 0.7874 0.4064)
			(stroke
				(width 0.1524)
				(type default)
			)
			(layer "F.SilkS")
		)
		(fp_line
			(start -0.67945 0.3048)
			(end -0.67945 -0.305054)
			(stroke
				(width 0.1)
				(type default)
			)
			(layer "F.Fab")
		)
		(fp_line
			(start -0.12065 0.3048)
			(end -0.67945 0.3048)
			(stroke
				(width 0.1)
				(type default)
			)
			(layer "F.Fab")
		)
		(fp_line
			(start 0.120396 0.3048)
			(end 0.120396 0.2794)
			(stroke
				(width 0.1)
				(type default)
			)
			(layer "F.Fab")
		)
		(fp_line
			(start 0.67945 0.3048)
			(end 0.120396 0.3048)
			(stroke
				(width 0.1)
				(type default)
			)
			(layer "F.Fab")
		)
		(fp_line
			(start -0.12065 0.2794)
			(end -0.12065 0.3048)
			(stroke
				(width 0.1)
				(type default)
			)
			(layer "F.Fab")
		)
		(fp_line
			(start 0.120396 0.2794)
			(end -0.12065 0.2794)
			(stroke
				(width 0.1)
				(type default)
			)
			(layer "F.Fab")
		)
		(fp_line
			(start -0.12065 -0.2794)
			(end 0.12065 -0.2794)
			(stroke
				(width 0.1)
				(type default)
			)
			(layer "F.Fab")
		)
		(fp_line
			(start 0.12065 -0.2794)
			(end 0.12065 -0.3048)
			(stroke
				(width 0.1)
				(type default)
			)
			(layer "F.Fab")
		)
		(fp_line
			(start 0.12065 -0.3048)
			(end 0.67945 -0.3048)
			(stroke
				(width 0.1)
				(type default)
			)
			(layer "F.Fab")
		)
		(fp_line
			(start 0.67945 -0.3048)
			(end 0.67945 0.3048)
			(stroke
				(width 0.1)
				(type default)
			)
			(layer "F.Fab")
		)
		(fp_line
			(start -0.67945 -0.305054)
			(end -0.12065 -0.305054)
			(stroke
				(width 0.1)
				(type default)
			)
			(layer "F.Fab")
		)
		(fp_line
			(start -0.12065 -0.305054)
			(end -0.12065 -0.2794)
			(stroke
				(width 0.1)
				(type default)
			)
			(layer "F.Fab")
		)
		(pad "1" smd circle
			(at -0.40005 0 270)
			(size 0 0)
			(layers "F.Cu" "F.Mask" "F.Paste")
			(net "SW_P12V_AUX_PVDDIO_P0_FLT")
		)
		(pad "2" smd circle
			(at 0.40005 0 270)
			(size 0 0)
			(layers "F.Cu" "F.Mask" "F.Paste")
			(net "GND")
		)
	)
)
